# T6G (Grand Teton) — schematic netlist excerpt (pin names and nets, part order shuffled) for the footprints in the layout excerpt that follows; sources: Cadence DE-HDL packaged netlist, KiCad conversion of 04192023_DAF0TMB3IC0_F0TG_MB_C_brd_V02_OCP.brd

J28  SCONN288_DDR506112002KQ  IO  pkg DDR288S_1-1VXC  page 100
  VIN_BULK0  = P12V_MEM_CPU1
  RFU0  = NC
  VIN_MGMT  = P3V3_AUX
  HSCL  = I3C_SPD_DDRC_CPU1_SCL
  HSDA  = I3C_SPD_DDRC_CPU1_SDA
  VSS0  = GND
  DQ0_A  = M_C_CPU1_SA_DQ<0>
  VSS1  = GND
  DQ1_A  = M_C_CPU1_SA_DQ<1>
  VSS2  = GND
  DQS0_A_T  = M_C_CPU1_SA_DQS_DP<0>
  DQS0_A_C  = M_C_CPU1_SA_DQS_DN<0>
  VSS3  = GND
  DQ4_A  = M_C_CPU1_SA_DQ<4>
  VSS4  = GND
  DQ5_A  = M_C_CPU1_SA_DQ<5>
  VSS5  = GND
  DQ8_A  = M_C_CPU1_SA_DQ<8>
  VSS6  = GND
  DQ9_A  = M_C_CPU1_SA_DQ<9>
  VSS7  = GND
  DQS1_A_T  = M_C_CPU1_SA_DQS_DP<1>
  DQS1_A_C  = M_C_CPU1_SA_DQS_DN<1>
  VSS8  = GND
  DQ12_A  = M_C_CPU1_SA_DQ<12>
  VSS9  = GND
  DQ13_A  = M_C_CPU1_SA_DQ<13>
  VSS10  = GND
  DQ16_A  = M_C_CPU1_SA_DQ<16>
  VSS11  = GND
  DQ17_A  = M_C_CPU1_SA_DQ<17>
  VSS12  = GND
  DQS2_A_T  = M_C_CPU1_SA_DQS_DP<2>
  DQS2_A_C  = M_C_CPU1_SA_DQS_DN<2>
  VSS13  = GND
  DQ20_A  = M_C_CPU1_SA_DQ<20>
  VSS14  = GND
  DQ21_A  = M_C_CPU1_SA_DQ<21>
  VSS15  = GND
  DQ24_A  = M_C_CPU1_SA_DQ<24>
  VSS16  = GND
  DQ25_A  = M_C_CPU1_SA_DQ<25>
  VSS17  = GND
  DQS3_A_T  = M_C_CPU1_SA_DQS_DP<3>
  DQS3_A_C  = M_C_CPU1_SA_DQS_DN<3>
  VSS18  = GND
  DQ28_A  = M_C_CPU1_SA_DQ<28>
  VSS19  = GND
  DQ29_A  = M_C_CPU1_SA_DQ<29>
  VSS20  = GND
  CB0_A  = M_C_CPU1_SA_CB<0>
  VSS21  = GND
  CB1_A  = M_C_CPU1_SA_CB<1>
  VSS22  = GND
  DQS4_A_T  = M_C_CPU1_SA_DQS_DP<4>
  DQS4_A_C  = M_C_CPU1_SA_DQS_DN<4>
  VSS23  = GND
  CB4_A  = M_C_CPU1_SA_CB<4>
  VSS24  = GND
  CB5_A  = M_C_CPU1_SA_CB<5>
  VSS25  = GND
  ALERT_N  = M_C_CPU1_ALERT_N
  VSS26  = GND
  CS0_A_N  = M_C_CPU1_SA_CS_N<0>
  VSS27  = GND
  CA0_A  = M_C_CPU1_SA_CA<0>
  VSS28  = GND
  CA2_A  = M_C_CPU1_SA_CA<2>
  VSS29  = GND
  CA4_A  = M_C_CPU1_SA_CA<4>
  VSS30  = GND
  CA6_A  = M_C_CPU1_SA_CA<6>
  VSS31  = GND
  PAR_A  = M_C_CPU1_SA_PAR
  VSS32  = GND
  CA0_B  = M_C_CPU1_SB_CA<0>
  VSS33  = GND
  CA2_B  = M_C_CPU1_SB_CA<2>
  VSS34  = GND
  CA4_B  = M_C_CPU1_SB_CA<4>
  VSS35  = GND
  CA6_B  = M_C_CPU1_SB_CA<6>
  VSS36  = GND
  CS0_B_N  = M_C_CPU1_SB_CS_N<0>
  VSS37  = GND
  \lbd||rsp_a_n\  = M_C_CPU1_SA_RSP<0>
  \lbs||rsp_b_n\  = M_C_CPU1_SB_RSP<0>
  VSS38  = GND
  CB4_B  = M_C_CPU1_SB_CB<4>
  VSS39  = GND
  CB5_B  = M_C_CPU1_SB_CB<5>
  VSS40  = GND
  \dqs9_b_t||tdqs9_b_t||dbi4_b_n\  = M_C_CPU1_SB_DQS_DP<9>
  \dqs9_b_c||tdqs9_b_c\  = M_C_CPU1_SB_DQS_DN<9>
  VSS41  = GND
  CB0_B  = M_C_CPU1_SB_CB<0>
  VSS42  = GND
  CB1_B  = M_C_CPU1_SB_CB<1>
  VSS43  = GND
  DQ0_B  = M_C_CPU1_SB_DQ<0>
  VSS44  = GND
  DQ1_B  = M_C_CPU1_SB_DQ<1>
  VSS45  = GND
  DQS0_B_T  = M_C_CPU1_SB_DQS_DP<0>
  DQS0_B_C  = M_C_CPU1_SB_DQS_DN<0>
  VSS46  = GND
  DQ4_B  = M_C_CPU1_SB_DQ<4>
  VSS47  = GND
  DQ5_B  = M_C_CPU1_SB_DQ<5>
  VSS48  = GND
  DQ8_B  = M_C_CPU1_SB_DQ<8>
  VSS49  = GND
  DQ9_B  = M_C_CPU1_SB_DQ<9>
  VSS50  = GND
  DQS1_B_T  = M_C_CPU1_SB_DQS_DP<1>
  DQS1_B_C  = M_C_CPU1_SB_DQS_DN<1>
  VSS51  = GND
  DQ12_B  = M_C_CPU1_SB_DQ<12>
  VSS52  = GND
  DQ13_B  = M_C_CPU1_SB_DQ<13>
  VSS53  = GND
  DQ16_B  = M_C_CPU1_SB_DQ<16>
  VSS54  = GND
  DQ17_B  = M_C_CPU1_SB_DQ<17>
  VSS55  = GND
  DQS2_B_T  = M_C_CPU1_SB_DQS_DP<2>
  DQS2_B_C  = M_C_CPU1_SB_DQS_DN<2>
  VSS56  = GND
  DQ20_B  = M_C_CPU1_SB_DQ<20>
  VSS57  = GND
  DQ21_B  = M_C_CPU1_SB_DQ<21>
  VSS58  = GND
  DQ24_B  = M_C_CPU1_SB_DQ<24>
  VSS59  = GND
  DQ25_B  = M_C_CPU1_SB_DQ<25>
  VSS60  = GND
  DQS3_B_T  = M_C_CPU1_SB_DQS_DP<3>
  DQS3_B_C  = M_C_CPU1_SB_DQS_DN<3>
  VSS61  = GND
  DQ28_B  = M_C_CPU1_SB_DQ<28>
  VSS62  = GND
  DQ29_B  = M_C_CPU1_SB_DQ<29>
  VSS63  = GND
  RFU1  = NC
  VIN_BULK1  = P12V_MEM_CPU1
  VIN_BULK2  = P12V_MEM_CPU1
  \pwr_good||fail_n\  = PWRGD_CHC_CPU1_DIMM
  HAS  = PD_CHC_CPU1_DIMM_SAA
  RFU2  = NC
  RFU3  = NC
  VSS64  = GND
  DQ2_A  = M_C_CPU1_SA_DQ<2>
  VSS65  = GND
  DQ3_A  = M_C_CPU1_SA_DQ<3>
  VSS66  = GND
  \dqs5_a_c||tdqs5_a_c||dqs5_a_t||tdqs5_a_t\  = M_C_CPU1_SA_DQS_DN<5>
  \dqs5_a_t||tdqs5_a_t\  = M_C_CPU1_SA_DQS_DP<5>
  VSS67  = GND
  DQ6_A  = M_C_CPU1_SA_DQ<6>
  VSS68  = GND
  DQ7_A  = M_C_CPU1_SA_DQ<7>
  VSS69  = GND
  DQ10_A  = M_C_CPU1_SA_DQ<10>
  VSS70  = GND
  DQ11_A  = M_C_CPU1_SA_DQ<11>
  VSS71  = GND
  \dqs6_a_c||tdqs6_a_c||dqs6_a_t||tdqs6_a_t\  = M_C_CPU1_SA_DQS_DN<6>
  \dqs6_a_t||tdqs6_a_t\  = M_C_CPU1_SA_DQS_DP<6>
  VSS72  = GND
  DQ14_A  = M_C_CPU1_SA_DQ<14>
  VSS73  = GND
  DQ15_A  = M_C_CPU1_SA_DQ<15>
  VSS74  = GND
  DQ18_A  = M_C_CPU1_SA_DQ<18>
  VSS75  = GND
  DQ19_A  = M_C_CPU1_SA_DQ<19>
  VSS76  = GND
  \dqs7_a_c||tdqs7_a_c\  = M_C_CPU1_SA_DQS_DN<7>
  \dqs7_a_t||tdqs7_a_t\  = M_C_CPU1_SA_DQS_DP<7>
  VSS77  = GND
  DQ22_A  = M_C_CPU1_SA_DQ<22>
  VSS78  = GND
  DQ23_A  = M_C_CPU1_SA_DQ<23>
  VSS79  = GND
  DQ26_A  = M_C_CPU1_SA_DQ<26>
  VSS80  = GND
  DQ27_A  = M_C_CPU1_SA_DQ<27>
  VSS81  = GND
  \dqs8_a_c||tdqs8_a_c\  = M_C_CPU1_SA_DQS_DN<8>
  \dqs8_a_t||tdqs8_a_t\  = M_C_CPU1_SA_DQS_DP<8>
  VSS82  = GND
  DQ30_A  = M_C_CPU1_SA_DQ<30>
  VSS83  = GND
  DQ31_A  = M_C_CPU1_SA_DQ<31>
  VSS84  = GND
  CB2_A  = M_C_CPU1_SA_CB<2>
  VSS85  = GND
  CB3_A  = M_C_CPU1_SA_CB<3>
  VSS86  = GND
  \dqs9_a_c||tdqs9_a_c\  = M_C_CPU1_SA_DQS_DN<9>
  \dqs9_a_t||tdqs9_a_t\  = M_C_CPU1_SA_DQS_DP<9>
  VSS87  = GND
  CB6_A  = M_C_CPU1_SA_CB<6>
  VSS88  = GND
  CB7_A  = M_C_CPU1_SA_CB<7>
  VSS89  = GND
  RESET_N  = M_C_CPU1_RESET_N
  VSS90  = GND
  CS1_A_N  = M_C_CPU1_SA_CS_N<1>
  VSS91  = GND
  CA1_A  = M_C_CPU1_SA_CA<1>
  VSS92  = GND
  CA3_A  = M_C_CPU1_SA_CA<3>
  VSS93  = GND
  CA5_A  = M_C_CPU1_SA_CA<5>
  VSS94  = GND
  CK_T  = M_C_CPU1_CLK_DP<0>
  CK_C  = M_C_CPU1_CLK_DN<0>
  VSS95  = GND
  RFU4  = NC
  CA1_B  = M_C_CPU1_SB_CA<1>
  VSS96  = GND
  CA3_B  = M_C_CPU1_SB_CA<3>
  VSS97  = GND
  CA5_B  = M_C_CPU1_SB_CA<5>
  VSS98  = GND
  PAR_B  = M_C_CPU1_SB_PAR
  VSS99  = GND
  CS1_B_N  = M_C_CPU1_SB_CS_N<1>
  VSS100  = GND
  RFU5  = NC
  RFU6  = NC
  VSS101  = GND
  CB6_B  = M_C_CPU1_SB_CB<6>
  VSS102  = GND
  CB7_B  = M_C_CPU1_SB_CB<7>
  VSS103  = GND
  DQS4_B_C  = M_C_CPU1_SB_DQS_DN<4>
  DQS4_B_T  = M_C_CPU1_SB_DQS_DP<4>
  VSS104  = GND
  CB2_B  = M_C_CPU1_SB_CB<2>
  VSS105  = GND
  CB3_B  = M_C_CPU1_SB_CB<3>
  VSS106  = GND
  DQ2_B  = M_C_CPU1_SB_DQ<2>
  VSS107  = GND
  DQ3_B  = M_C_CPU1_SB_DQ<3>
  VSS108  = GND
  \dqs5_b_c||tdqs5_b_c\  = M_C_CPU1_SB_DQS_DN<5>
  \dqs5_b_t||tdqs5_b_t\  = M_C_CPU1_SB_DQS_DP<5>
  VSS109  = GND
  DQ6_B  = M_C_CPU1_SB_DQ<6>
  VSS110  = GND
  DQ7_B  = M_C_CPU1_SB_DQ<7>
  VSS111  = GND
  DQ10_B  = M_C_CPU1_SB_DQ<10>
  VSS112  = GND
  DQ11_B  = M_C_CPU1_SB_DQ<11>
  VSS113  = GND
  \dqs6_b_c||tdqs6_b_c\  = M_C_CPU1_SB_DQS_DN<6>
  \dqs6_b_t||tdqs6_b_t\  = M_C_CPU1_SB_DQS_DP<6>
  VSS114  = GND
  DQ14_B  = M_C_CPU1_SB_DQ<14>
  VSS115  = GND
  DQ15_B  = M_C_CPU1_SB_DQ<15>
  VSS116  = GND
  DQ18_B  = M_C_CPU1_SB_DQ<18>
  VSS117  = GND
  DQ19_B  = M_C_CPU1_SB_DQ<19>
  VSS118  = GND
  \dqs7_b_c||tdqs7_b_c\  = M_C_CPU1_SB_DQS_DN<7>
  \dqs7_b_t||tdqs7_b_t\  = M_C_CPU1_SB_DQS_DP<7>
  VSS119  = GND
  DQ22_B  = M_C_CPU1_SB_DQ<22>
  VSS120  = GND
  DQ23_B  = M_C_CPU1_SB_DQ<23>
  VSS121  = GND
  DQ26_B  = M_C_CPU1_SB_DQ<26>
  VSS122  = GND
  DQ27_B  = M_C_CPU1_SB_DQ<27>
  VSS123  = GND
  \dqs8_b_c||tdqs8_b_c\  = M_C_CPU1_SB_DQS_DN<8>
  \dqs8_b_t||tdqs8_b_t\  = M_C_CPU1_SB_DQS_DP<8>
  VSS124  = GND
  DQ30_B  = M_C_CPU1_SB_DQ<30>
  VSS125  = GND
  DQ31_B  = M_C_CPU1_SB_DQ<31>
  VSS126  = GND
  G1  = GND
  G2  = GND
  G3  = GND

(kicad_pcb
	(version 20260206)
	(generator "pcbnew")
	(generator_version "10.0")
	(general
		(thickness 1.6)
		(legacy_teardrops no)
	)
	(paper "A4")
	(title_block
		(title "04192023_DAF0TMB3IC0_F0TG_MB_C_brd_V02_OCP.brd")
		(comment 1 "Grand Teton / footprint 4188 of 8354 (J28), pads 139-184 of 291")
	)
	(layers
		(0 "F.Cu" signal "TOP")
		(4 "In1.Cu" signal "GND")
		(6 "In2.Cu" signal "IN1")
		(8 "In3.Cu" signal "GND1")
		(10 "In4.Cu" signal "IN2")
		(12 "In5.Cu" signal "GND2")
		(14 "In6.Cu" signal "IN3")
		(16 "In7.Cu" signal "GND3")
		(18 "In8.Cu" signal "VCC")
		(20 "In9.Cu" signal "VCC1")
		(22 "In10.Cu" signal "GND4")
		(24 "In11.Cu" signal "IN4")
		(26 "In12.Cu" signal "GND5")
		(28 "In13.Cu" signal "IN5")
		(30 "In14.Cu" signal "GND6")
		(32 "In15.Cu" signal "IN6")
		(34 "In16.Cu" signal "GND7")
		(2 "B.Cu" signal "BOTTOM")
		(9 "F.Adhes" user "F.Adhesive")
		(11 "B.Adhes" user "B.Adhesive")
		(13 "F.Paste" user "Package Geometry/Pastemask Top")
		(15 "B.Paste" user "Package Geometry/Pastemask Bottom")
		(5 "F.SilkS" user "Ref Des/Silkscreen Top")
		(7 "B.SilkS" user "Ref Des/Silkscreen Bottom")
		(1 "F.Mask" user "Board Geometry/Soldermask Top")
		(3 "B.Mask" user "Board Geometry/Soldermask Bottom")
		(17 "Dwgs.User" user "User.Drawings")
		(19 "Cmts.User" user "User.Comments")
		(21 "Eco1.User" user "User.Eco1")
		(23 "Eco2.User" user "User.Eco2")
		(25 "Edge.Cuts" user "Board Geometry/Outline")
		(27 "Margin" user)
		(31 "F.CrtYd" user "Package Geometry/Place Bound Top")
		(29 "B.CrtYd" user "Package Geometry/Place Bound Bottom")
		(35 "F.Fab" user "Ref Des/Assembly Top")
		(33 "B.Fab" user "Ref Des/Assembly Bottom")
	)
	(footprint ""
		(layer "F.Cu")
		(at 42.289984 -255.560322 180)
		(property "Reference" "J28"
			(at -2.876296 -82.230976 0)
			(unlocked yes)
			(layer "F.SilkS")
			(effects
				(font
					(size 0.7874 0.5842)
					(thickness 0.1524)
				)
			)
		)
		(property "Value" ""
			(at 0 0 180)
			(layer "F.Fab")
			(effects
				(font
					(size 1.27 1.27)
				)
			)
		)
		(duplicate_pad_numbers_are_jumpers no)
		(pad "139" smd rect
			(at -2.050034 59.075066 90)
			(size 0.519938 1.4986)
			(layers "F.Cu" "F.Mask" "F.Paste")
			(net "GND")
		)
		(pad "140" smd rect
			(at -2.050034 59.92495 90)
			(size 0.519938 1.4986)
			(layers "F.Cu" "F.Mask" "F.Paste")
			(net "M_C_CPU1_SB_DQ<28>")
		)
		(pad "141" smd rect
			(at -2.050034 60.775088 90)
			(size 0.519938 1.4986)
			(layers "F.Cu" "F.Mask" "F.Paste")
			(net "GND")
		)
		(pad "142" smd rect
			(at -2.050034 61.624972 90)
			(size 0.519938 1.4986)
			(layers "F.Cu" "F.Mask" "F.Paste")
			(net "M_C_CPU1_SB_DQ<29>")
		)
		(pad "143" smd rect
			(at -2.050034 62.47511 90)
			(size 0.519938 1.4986)
			(layers "F.Cu" "F.Mask" "F.Paste")
			(net "GND")
		)
		(pad "144" smd rect
			(at -2.050034 63.324994 90)
			(size 0.519938 1.4986)
			(layers "F.Cu" "F.Mask" "F.Paste")
			(net "Net_2285")
		)
		(pad "145" smd rect
			(at 2.050034 -63.324994 90)
			(size 0.519938 1.4986)
			(layers "F.Cu" "F.Mask" "F.Paste")
			(net "P12V_MEM_CPU1")
		)
		(pad "146" smd rect
			(at 2.050034 -62.47511 90)
			(size 0.519938 1.4986)
			(layers "F.Cu" "F.Mask" "F.Paste")
			(net "P12V_MEM_CPU1")
		)
		(pad "147" smd rect
			(at 2.050034 -61.624972 90)
			(size 0.519938 1.4986)
			(layers "F.Cu" "F.Mask" "F.Paste")
			(net "PWRGD_CHC_CPU1_DIMM")
		)
		(pad "148" smd rect
			(at 2.050034 -60.775088 90)
			(size 0.519938 1.4986)
			(layers "F.Cu" "F.Mask" "F.Paste")
			(net "PD_CHC_CPU1_DIMM_SAA")
		)
		(pad "149" smd rect
			(at 2.050034 -59.92495 90)
			(size 0.519938 1.4986)
			(layers "F.Cu" "F.Mask" "F.Paste")
			(net "Net_2286")
		)
		(pad "150" smd rect
			(at 2.050034 -59.075066 90)
			(size 0.519938 1.4986)
			(layers "F.Cu" "F.Mask" "F.Paste")
			(net "Net_2287")
		)
		(pad "151" smd rect
			(at 2.050034 -58.224928 90)
			(size 0.519938 1.4986)
			(layers "F.Cu" "F.Mask" "F.Paste")
			(net "GND")
		)
		(pad "152" smd rect
			(at 2.050034 -57.375044 90)
			(size 0.519938 1.4986)
			(layers "F.Cu" "F.Mask" "F.Paste")
			(net "M_C_CPU1_SA_DQ<2>")
		)
		(pad "153" smd rect
			(at 2.050034 -56.524906 90)
			(size 0.519938 1.4986)
			(layers "F.Cu" "F.Mask" "F.Paste")
			(net "GND")
		)
		(pad "154" smd rect
			(at 2.050034 -55.675022 90)
			(size 0.519938 1.4986)
			(layers "F.Cu" "F.Mask" "F.Paste")
			(net "M_C_CPU1_SA_DQ<3>")
		)
		(pad "155" smd rect
			(at 2.050034 -54.824884 90)
			(size 0.519938 1.4986)
			(layers "F.Cu" "F.Mask" "F.Paste")
			(net "GND")
		)
		(pad "156" smd rect
			(at 2.050034 -53.975 90)
			(size 0.519938 1.4986)
			(layers "F.Cu" "F.Mask" "F.Paste")
			(net "M_C_CPU1_SA_DQS_DN<5>")
		)
		(pad "157" smd rect
			(at 2.050034 -53.125116 90)
			(size 0.519938 1.4986)
			(layers "F.Cu" "F.Mask" "F.Paste")
			(net "M_C_CPU1_SA_DQS_DP<5>")
		)
		(pad "158" smd rect
			(at 2.050034 -52.274978 90)
			(size 0.519938 1.4986)
			(layers "F.Cu" "F.Mask" "F.Paste")
			(net "GND")
		)
		(pad "159" smd rect
			(at 2.050034 -51.425094 90)
			(size 0.519938 1.4986)
			(layers "F.Cu" "F.Mask" "F.Paste")
			(net "M_C_CPU1_SA_DQ<6>")
		)
		(pad "160" smd rect
			(at 2.050034 -50.574956 90)
			(size 0.519938 1.4986)
			(layers "F.Cu" "F.Mask" "F.Paste")
			(net "GND")
		)
		(pad "161" smd rect
			(at 2.050034 -49.725072 90)
			(size 0.519938 1.4986)
			(layers "F.Cu" "F.Mask" "F.Paste")
			(net "M_C_CPU1_SA_DQ<7>")
		)
		(pad "162" smd rect
			(at 2.050034 -48.874934 90)
			(size 0.519938 1.4986)
			(layers "F.Cu" "F.Mask" "F.Paste")
			(net "GND")
		)
		(pad "163" smd rect
			(at 2.050034 -48.02505 90)
			(size 0.519938 1.4986)
			(layers "F.Cu" "F.Mask" "F.Paste")
			(net "M_C_CPU1_SA_DQ<10>")
		)
		(pad "164" smd rect
			(at 2.050034 -47.174912 90)
			(size 0.519938 1.4986)
			(layers "F.Cu" "F.Mask" "F.Paste")
			(net "GND")
		)
		(pad "165" smd rect
			(at 2.050034 -46.325028 90)
			(size 0.519938 1.4986)
			(layers "F.Cu" "F.Mask" "F.Paste")
			(net "M_C_CPU1_SA_DQ<11>")
		)
		(pad "166" smd rect
			(at 2.050034 -45.47489 90)
			(size 0.519938 1.4986)
			(layers "F.Cu" "F.Mask" "F.Paste")
			(net "GND")
		)
		(pad "167" smd rect
			(at 2.050034 -44.625006 90)
			(size 0.519938 1.4986)
			(layers "F.Cu" "F.Mask" "F.Paste")
			(net "M_C_CPU1_SA_DQS_DN<6>")
		)
		(pad "168" smd rect
			(at 2.050034 -43.775122 90)
			(size 0.519938 1.4986)
			(layers "F.Cu" "F.Mask" "F.Paste")
			(net "M_C_CPU1_SA_DQS_DP<6>")
		)
		(pad "169" smd rect
			(at 2.050034 -42.924984 90)
			(size 0.519938 1.4986)
			(layers "F.Cu" "F.Mask" "F.Paste")
			(net "GND")
		)
		(pad "170" smd rect
			(at 2.050034 -42.0751 90)
			(size 0.519938 1.4986)
			(layers "F.Cu" "F.Mask" "F.Paste")
			(net "M_C_CPU1_SA_DQ<14>")
		)
		(pad "171" smd rect
			(at 2.050034 -41.224962 90)
			(size 0.519938 1.4986)
			(layers "F.Cu" "F.Mask" "F.Paste")
			(net "GND")
		)
		(pad "172" smd rect
			(at 2.050034 -40.375078 90)
			(size 0.519938 1.4986)
			(layers "F.Cu" "F.Mask" "F.Paste")
			(net "M_C_CPU1_SA_DQ<15>")
		)
		(pad "173" smd rect
			(at 2.050034 -39.52494 90)
			(size 0.519938 1.4986)
			(layers "F.Cu" "F.Mask" "F.Paste")
			(net "GND")
		)
		(pad "174" smd rect
			(at 2.050034 -38.675056 90)
			(size 0.519938 1.4986)
			(layers "F.Cu" "F.Mask" "F.Paste")
			(net "M_C_CPU1_SA_DQ<18>")
		)
		(pad "175" smd rect
			(at 2.050034 -37.824918 90)
			(size 0.519938 1.4986)
			(layers "F.Cu" "F.Mask" "F.Paste")
			(net "GND")
		)
		(pad "176" smd rect
			(at 2.050034 -36.975034 90)
			(size 0.519938 1.4986)
			(layers "F.Cu" "F.Mask" "F.Paste")
			(net "M_C_CPU1_SA_DQ<19>")
		)
		(pad "177" smd rect
			(at 2.050034 -36.124896 90)
			(size 0.519938 1.4986)
			(layers "F.Cu" "F.Mask" "F.Paste")
			(net "GND")
		)
		(pad "178" smd rect
			(at 2.050034 -35.275012 90)
			(size 0.519938 1.4986)
			(layers "F.Cu" "F.Mask" "F.Paste")
			(net "M_C_CPU1_SA_DQS_DN<7>")
		)
		(pad "179" smd rect
			(at 2.050034 -34.425128 90)
			(size 0.519938 1.4986)
			(layers "F.Cu" "F.Mask" "F.Paste")
			(net "M_C_CPU1_SA_DQS_DP<7>")
		)
		(pad "180" smd rect
			(at 2.050034 -33.57499 90)
			(size 0.519938 1.4986)
			(layers "F.Cu" "F.Mask" "F.Paste")
			(net "GND")
		)
		(pad "181" smd rect
			(at 2.050034 -32.725106 90)
			(size 0.519938 1.4986)
			(layers "F.Cu" "F.Mask" "F.Paste")
			(net "M_C_CPU1_SA_DQ<22>")
		)
		(pad "182" smd rect
			(at 2.050034 -31.874968 90)
			(size 0.519938 1.4986)
			(layers "F.Cu" "F.Mask" "F.Paste")
			(net "GND")
		)
		(pad "183" smd rect
			(at 2.050034 -31.025084 90)
			(size 0.519938 1.4986)
			(layers "F.Cu" "F.Mask" "F.Paste")
			(net "M_C_CPU1_SA_DQ<23>")
		)
		(pad "184" smd rect
			(at 2.050034 -30.174946 90)
			(size 0.519938 1.4986)
			(layers "F.Cu" "F.Mask" "F.Paste")
			(net "GND")
		)
	)
)
